# S9S_MB_2U (Grand Teton) — schematic netlist excerpt (pin names and nets, part order shuffled) for the footprints in the layout excerpt that follows; sources: Cadence DE-HDL packaged netlist, KiCad conversion of 03242023_DA0F0TMBIJ0_F0T_Motherboard_J_brd_V01_OCP.brd

C410  Q_CAP  22UF 4V 20% X6S  pkg C0402  page 74 : A = PVCCINFAON_CPU0 ; B = GND
R1399  Q_RES  10K 1% CHIP  pkg 0402LF  page 220 : A = FM_PFR_DSW_PWROK_N ; B = P3V3_AUX

(kicad_pcb
	(version 20260206)
	(generator "pcbnew")
	(generator_version "10.0")
	(general
		(thickness 1.6)
		(legacy_teardrops no)
	)
	(paper "A4")
	(title_block
		(title "03242023_DA0F0TMBIJ0_F0T_Motherboard_J_brd_V01_OCP.brd")
		(comment 1 "Grand Teton / footprints 2445-2446 of 6105")
	)
	(layers
		(0 "F.Cu" signal "TOP")
		(4 "In1.Cu" signal "GND")
		(6 "In2.Cu" signal "IN1")
		(8 "In3.Cu" signal "GND1")
		(10 "In4.Cu" signal "IN2")
		(12 "In5.Cu" signal "GND2")
		(14 "In6.Cu" signal "IN3")
		(16 "In7.Cu" signal "GND3")
		(18 "In8.Cu" signal "VCC")
		(20 "In9.Cu" signal "VCC1")
		(22 "In10.Cu" signal "GND4")
		(24 "In11.Cu" signal "IN4")
		(26 "In12.Cu" signal "GND5")
		(28 "In13.Cu" signal "IN5")
		(30 "In14.Cu" signal "GND6")
		(32 "In15.Cu" signal "IN6")
		(34 "In16.Cu" signal "GND7")
		(2 "B.Cu" signal "BOTTOM")
		(9 "F.Adhes" user "F.Adhesive")
		(11 "B.Adhes" user "B.Adhesive")
		(13 "F.Paste" user "Package Geometry/Pastemask Top")
		(15 "B.Paste" user "Package Geometry/Pastemask Bottom")
		(5 "F.SilkS" user "Ref Des/Silkscreen Top")
		(7 "B.SilkS" user "Ref Des/Silkscreen Bottom")
		(1 "F.Mask" user "Board Geometry/Soldermask Top")
		(3 "B.Mask" user "Board Geometry/Soldermask Bottom")
		(17 "Dwgs.User" user "User.Drawings")
		(19 "Cmts.User" user "User.Comments")
		(21 "Eco1.User" user "User.Eco1")
		(23 "Eco2.User" user "User.Eco2")
		(25 "Edge.Cuts" user "Board Geometry/Outline")
		(27 "Margin" user)
		(31 "F.CrtYd" user "Package Geometry/Place Bound Top")
		(29 "B.CrtYd" user "Package Geometry/Place Bound Bottom")
		(35 "F.Fab" user "Ref Des/Assembly Top")
		(33 "B.Fab" user "Ref Des/Assembly Bottom")
	)
	(footprint ""
		(layer "F.Cu")
		(at 174.04588 -130.266948 90)
		(property "Reference" "R1399"
			(at 0 0 90)
			(layer "F.SilkS")
			(hide yes)
			(effects
				(font
					(size 1.27 1.27)
				)
			)
		)
		(property "Value" ""
			(at 0 0 90)
			(layer "F.Fab")
			(effects
				(font
					(size 1.27 1.27)
				)
			)
		)
		(duplicate_pad_numbers_are_jumpers no)
		(fp_line
			(start 0.7874 -0.4064)
			(end 0.7874 0.4064)
			(stroke
				(width 0.1524)
				(type default)
			)
			(layer "F.SilkS")
		)
		(fp_line
			(start -0.7874 -0.4064)
			(end 0.7874 -0.4064)
			(stroke
				(width 0.1524)
				(type default)
			)
			(layer "F.SilkS")
		)
		(fp_line
			(start 0.7874 0.4064)
			(end -0.7874 0.4064)
			(stroke
				(width 0.1524)
				(type default)
			)
			(layer "F.SilkS")
		)
		(fp_line
			(start -0.7874 0.4064)
			(end -0.7874 -0.4064)
			(stroke
				(width 0.1524)
				(type default)
			)
			(layer "F.SilkS")
		)
		(fp_line
			(start -0.12065 -0.305054)
			(end -0.12065 -0.2794)
			(stroke
				(width 0.1)
				(type default)
			)
			(layer "F.Fab")
		)
		(fp_line
			(start -0.67945 -0.305054)
			(end -0.12065 -0.305054)
			(stroke
				(width 0.1)
				(type default)
			)
			(layer "F.Fab")
		)
		(fp_line
			(start 0.67945 -0.3048)
			(end 0.67945 0.3048)
			(stroke
				(width 0.1)
				(type default)
			)
			(layer "F.Fab")
		)
		(fp_line
			(start 0.12065 -0.3048)
			(end 0.67945 -0.3048)
			(stroke
				(width 0.1)
				(type default)
			)
			(layer "F.Fab")
		)
		(fp_line
			(start 0.12065 -0.2794)
			(end 0.12065 -0.3048)
			(stroke
				(width 0.1)
				(type default)
			)
			(layer "F.Fab")
		)
		(fp_line
			(start -0.12065 -0.2794)
			(end 0.12065 -0.2794)
			(stroke
				(width 0.1)
				(type default)
			)
			(layer "F.Fab")
		)
		(fp_line
			(start 0.120396 0.2794)
			(end -0.12065 0.2794)
			(stroke
				(width 0.1)
				(type default)
			)
			(layer "F.Fab")
		)
		(fp_line
			(start -0.12065 0.2794)
			(end -0.12065 0.3048)
			(stroke
				(width 0.1)
				(type default)
			)
			(layer "F.Fab")
		)
		(fp_line
			(start 0.67945 0.3048)
			(end 0.120396 0.3048)
			(stroke
				(width 0.1)
				(type default)
			)
			(layer "F.Fab")
		)
		(fp_line
			(start 0.120396 0.3048)
			(end 0.120396 0.2794)
			(stroke
				(width 0.1)
				(type default)
			)
			(layer "F.Fab")
		)
		(fp_line
			(start -0.12065 0.3048)
			(end -0.67945 0.3048)
			(stroke
				(width 0.1)
				(type default)
			)
			(layer "F.Fab")
		)
		(fp_line
			(start -0.67945 0.3048)
			(end -0.67945 -0.305054)
			(stroke
				(width 0.1)
				(type default)
			)
			(layer "F.Fab")
		)
		(pad "1" smd circle
			(at -0.40005 0 90)
			(size 0 0)
			(layers "F.Cu" "F.Mask" "F.Paste")
			(net "FM_PFR_DSW_PWROK_N")
		)
		(pad "2" smd circle
			(at 0.40005 0 90)
			(size 0 0)
			(layers "F.Cu" "F.Mask" "F.Paste")
			(net "P3V3_AUX")
		)
	)
	(footprint ""
		(layer "F.Cu")
		(at 364.50143 -238.162338 90)
		(property "Reference" "C410"
			(at 0 0 90)
			(layer "F.SilkS")
			(hide yes)
			(effects
				(font
					(size 1.27 1.27)
				)
			)
		)
		(property "Value" ""
			(at 0 0 90)
			(layer "F.Fab")
			(effects
				(font
					(size 1.27 1.27)
				)
			)
		)
		(duplicate_pad_numbers_are_jumpers no)
		(fp_line
			(start 0.7874 -0.4064)
			(end 0.7874 0.4064)
			(stroke
				(width 0.1524)
				(type default)
			)
			(layer "F.SilkS")
		)
		(fp_line
			(start -0.7874 -0.4064)
			(end 0.7874 -0.4064)
			(stroke
				(width 0.1524)
				(type default)
			)
			(layer "F.SilkS")
		)
		(fp_line
			(start 0.7874 0.4064)
			(end -0.7874 0.4064)
			(stroke
				(width 0.1524)
				(type default)
			)
			(layer "F.SilkS")
		)
		(fp_line
			(start -0.7874 0.4064)
			(end -0.7874 -0.4064)
			(stroke
				(width 0.1524)
				(type default)
			)
			(layer "F.SilkS")
		)
		(fp_line
			(start -0.12065 -0.305054)
			(end -0.12065 -0.2794)
			(stroke
				(width 0.1)
				(type default)
			)
			(layer "F.Fab")
		)
		(fp_line
			(start -0.67945 -0.305054)
			(end -0.12065 -0.305054)
			(stroke
				(width 0.1)
				(type default)
			)
			(layer "F.Fab")
		)
		(fp_line
			(start 0.67945 -0.3048)
			(end 0.67945 0.3048)
			(stroke
				(width 0.1)
				(type default)
			)
			(layer "F.Fab")
		)
		(fp_line
			(start 0.12065 -0.3048)
			(end 0.67945 -0.3048)
			(stroke
				(width 0.1)
				(type default)
			)
			(layer "F.Fab")
		)
		(fp_line
			(start 0.12065 -0.2794)
			(end 0.12065 -0.3048)
			(stroke
				(width 0.1)
				(type default)
			)
			(layer "F.Fab")
		)
		(fp_line
			(start -0.12065 -0.2794)
			(end 0.12065 -0.2794)
			(stroke
				(width 0.1)
				(type default)
			)
			(layer "F.Fab")
		)
		(fp_line
			(start 0.120396 0.2794)
			(end -0.12065 0.2794)
			(stroke
				(width 0.1)
				(type default)
			)
			(layer "F.Fab")
		)
		(fp_line
			(start -0.12065 0.2794)
			(end -0.12065 0.3048)
			(stroke
				(width 0.1)
				(type default)
			)
			(layer "F.Fab")
		)
		(fp_line
			(start 0.67945 0.3048)
			(end 0.120396 0.3048)
			(stroke
				(width 0.1)
				(type default)
			)
			(layer "F.Fab")
		)
		(fp_line
			(start 0.120396 0.3048)
			(end 0.120396 0.2794)
			(stroke
				(width 0.1)
				(type default)
			)
			(layer "F.Fab")
		)
		(fp_line
			(start -0.12065 0.3048)
			(end -0.67945 0.3048)
			(stroke
				(width 0.1)
				(type default)
			)
			(layer "F.Fab")
		)
		(fp_line
			(start -0.67945 0.3048)
			(end -0.67945 -0.305054)
			(stroke
				(width 0.1)
				(type default)
			)
			(layer "F.Fab")
		)
		(pad "1" smd circle
			(at -0.40005 0 90)
			(size 0 0)
			(layers "F.Cu" "F.Mask" "F.Paste")
			(net "PVCCINFAON_CPU0")
		)
		(pad "2" smd circle
			(at 0.40005 0 90)
			(size 0 0)
			(layers "F.Cu" "F.Mask" "F.Paste")
			(net "GND")
		)
	)
)
